(kicad_pcb
	(version 20260206)
	(generator "pcbnew")
	(generator_version "10.0")
	(general
		(thickness 1.6)
		(legacy_teardrops no)
	)
	(paper "A4")
	(title_block
		(title "Bryce Canyon_IOM_IOC_16318-2_OCP.brd")
		(comment 1 "Bryce Canyon / footprints 1485-1493 of 1605")
	)
	(layers
		(0 "F.Cu" signal "TOP")
		(4 "In1.Cu" signal "L2GND")
		(6 "In2.Cu" signal "L3")
		(8 "In3.Cu" signal "L4VCC")
		(10 "In4.Cu" signal "L5VCC")
		(12 "In5.Cu" signal "L6")
		(14 "In6.Cu" signal "L7GND")
		(2 "B.Cu" signal "BOTTOM")
		(9 "F.Adhes" user "F.Adhesive")
		(11 "B.Adhes" user "B.Adhesive")
		(13 "F.Paste" user "Package Geometry/Pastemask Top")
		(15 "B.Paste" user "Package Geometry/Pastemask Bottom")
		(5 "F.SilkS" user "Ref Des/Silkscreen Top")
		(7 "B.SilkS" user "Ref Des/Silkscreen Bottom")
		(1 "F.Mask" user "Board Geometry/Soldermask Top")
		(3 "B.Mask" user "Board Geometry/Soldermask Bottom")
		(17 "Dwgs.User" user "User.Drawings")
		(19 "Cmts.User" user "User.Comments")
		(21 "Eco1.User" user "User.Eco1")
		(23 "Eco2.User" user "User.Eco2")
		(25 "Edge.Cuts" user "Board Geometry/Outline")
		(27 "Margin" user)
		(31 "F.CrtYd" user "Package Geometry/Place Bound Top")
		(29 "B.CrtYd" user "Package Geometry/Place Bound Bottom")
		(35 "F.Fab" user "Ref Des/Assembly Top")
		(33 "B.Fab" user "Ref Des/Assembly Bottom")
	)
	(footprint ""
		(layer "B.Cu")
		(at 90.880184 -138.48588 -90)
		(property "Reference" "R721"
			(at 0 0 90)
			(layer "B.SilkS")
			(hide yes)
			(effects
				(font
					(size 1.27 1.27)
				)
				(justify mirror)
			)
		)
		(property "Value" "4K7R2F-GP"
			(at -0.064008 -3.993896 270)
			(unlocked yes)
			(layer "B.Fab")
			(hide yes)
			(effects
				(font
					(size 1.016 1.016)
					(thickness 0.1524)
				)
				(justify mirror)
			)
		)
		(property "Device Type" "R402H16"
			(at -0.064008 -5.517896 270)
			(unlocked yes)
			(layer "B.Fab")
			(hide yes)
			(effects
				(font
					(size 1.016 1.016)
					(thickness 0.1524)
				)
				(justify mirror)
			)
		)
		(duplicate_pad_numbers_are_jumpers no)
		(fp_line
			(start -0.508 -0.9398)
			(end 0.508 -0.9398)
			(stroke
				(width 0.1524)
				(type default)
			)
			(layer "B.SilkS")
		)
		(fp_line
			(start 0.508 -0.9398)
			(end 0.508 0.9398)
			(stroke
				(width 0.1524)
				(type default)
			)
			(layer "B.SilkS")
		)
		(fp_rect
			(start 0.508 0.9398)
			(end -0.508 -0.9398)
			(stroke
				(width 0)
				(type default)
			)
			(fill no)
			(layer "B.CrtYd")
		)
		(fp_rect
			(start 0.508 0.9398)
			(end -0.508 -0.9398)
			(stroke
				(width 0)
				(type default)
			)
			(fill no)
			(layer "B.Fab")
		)
		(pad "1" smd custom
			(at 0 -0.4445 90)
			(size 0.1397 0.1397)
			(layers "B.Cu" "B.Mask" "B.Paste")
			(net "P3V3_STBY")
			(options
				(clearance outline)
				(anchor circle)
			)
			(primitives
				(gr_poly
					(pts
						(arc
							(start -0.1778 0.2794)
							(mid -0.249642 0.249642)
							(end -0.2794 0.1778)
						)
						(arc
							(start -0.2794 -0.1778)
							(mid -0.249642 -0.249642)
							(end -0.1778 -0.2794)
						)
						(arc
							(start 0.1778 -0.2794)
							(mid 0.249642 -0.249642)
							(end 0.2794 -0.1778)
						)
						(arc
							(start 0.2794 0.1778)
							(mid 0.249642 0.249642)
							(end 0.1778 0.2794)
						)
					)
					(width 0)
					(fill yes)
				)
			)
		)
		(pad "2" smd custom
			(at 0 0.4445 90)
			(size 0.1397 0.1397)
			(layers "B.Cu" "B.Mask" "B.Paste")
			(net "DEBUG_HDR_UART_SEL")
			(options
				(clearance outline)
				(anchor circle)
			)
			(primitives
				(gr_poly
					(pts
						(arc
							(start -0.1778 0.2794)
							(mid -0.249642 0.249642)
							(end -0.2794 0.1778)
						)
						(arc
							(start -0.2794 -0.1778)
							(mid -0.249642 -0.249642)
							(end -0.1778 -0.2794)
						)
						(arc
							(start 0.1778 -0.2794)
							(mid 0.249642 -0.249642)
							(end 0.2794 -0.1778)
						)
						(arc
							(start 0.2794 0.1778)
							(mid 0.249642 0.249642)
							(end 0.1778 0.2794)
						)
					)
					(width 0)
					(fill yes)
				)
			)
		)
	)
	(footprint ""
		(layer "B.Cu")
		(at 174.5742 -67.3354 90)
		(property "Reference" "R577"
			(at 0 0 90)
			(layer "B.SilkS")
			(hide yes)
			(effects
				(font
					(size 1.27 1.27)
				)
				(justify mirror)
			)
		)
		(property "Value" "2K2R2F-GP"
			(at -0.064008 -3.993896 90)
			(unlocked yes)
			(layer "B.Fab")
			(hide yes)
			(effects
				(font
					(size 1.016 1.016)
					(thickness 0.1524)
				)
				(justify mirror)
			)
		)
		(property "Device Type" "R402H16"
			(at -0.064008 -5.517896 90)
			(unlocked yes)
			(layer "B.Fab")
			(hide yes)
			(effects
				(font
					(size 1.016 1.016)
					(thickness 0.1524)
				)
				(justify mirror)
			)
		)
		(duplicate_pad_numbers_are_jumpers no)
		(fp_line
			(start 0.508 -0.9398)
			(end 0.508 0.9398)
			(stroke
				(width 0.1524)
				(type default)
			)
			(layer "B.SilkS")
		)
		(fp_line
			(start -0.508 -0.9398)
			(end 0.508 -0.9398)
			(stroke
				(width 0.1524)
				(type default)
			)
			(layer "B.SilkS")
		)
		(fp_rect
			(start 0.508 0.9398)
			(end -0.508 -0.9398)
			(stroke
				(width 0)
				(type default)
			)
			(fill no)
			(layer "B.CrtYd")
		)
		(fp_rect
			(start 0.508 0.9398)
			(end -0.508 -0.9398)
			(stroke
				(width 0)
				(type default)
			)
			(fill no)
			(layer "B.Fab")
		)
		(pad "1" smd custom
			(at 0 -0.4445 270)
			(size 0.1397 0.1397)
			(layers "B.Cu" "B.Mask" "B.Paste")
			(net "P1V8")
			(options
				(clearance outline)
				(anchor circle)
			)
			(primitives
				(gr_poly
					(pts
						(arc
							(start -0.1778 0.2794)
							(mid -0.249642 0.249642)
							(end -0.2794 0.1778)
						)
						(arc
							(start -0.2794 -0.1778)
							(mid -0.249642 -0.249642)
							(end -0.1778 -0.2794)
						)
						(arc
							(start 0.1778 -0.2794)
							(mid 0.249642 -0.249642)
							(end 0.2794 -0.1778)
						)
						(arc
							(start 0.2794 0.1778)
							(mid 0.249642 0.249642)
							(end 0.1778 0.2794)
						)
					)
					(width 0)
					(fill yes)
				)
			)
		)
		(pad "2" smd custom
			(at 0 0.4445 270)
			(size 0.1397 0.1397)
			(layers "B.Cu" "B.Mask" "B.Paste")
			(net "IOC_SDA_2")
			(options
				(clearance outline)
				(anchor circle)
			)
			(primitives
				(gr_poly
					(pts
						(arc
							(start -0.1778 0.2794)
							(mid -0.249642 0.249642)
							(end -0.2794 0.1778)
						)
						(arc
							(start -0.2794 -0.1778)
							(mid -0.249642 -0.249642)
							(end -0.1778 -0.2794)
						)
						(arc
							(start 0.1778 -0.2794)
							(mid 0.249642 -0.249642)
							(end 0.2794 -0.1778)
						)
						(arc
							(start 0.2794 0.1778)
							(mid 0.249642 0.249642)
							(end 0.1778 0.2794)
						)
					)
					(width 0)
					(fill yes)
				)
			)
		)
	)
	(footprint ""
		(layer "B.Cu")
		(at 56.80456 -156.29128 -90)
		(property "Reference" "L2"
			(at 0 0 90)
			(layer "B.SilkS")
			(hide yes)
			(effects
				(font
					(size 1.27 1.27)
				)
				(justify mirror)
			)
		)
		(property "Value" "MMZ2012S601ATA1N-GP"
			(at 0 -4.2418 270)
			(unlocked yes)
			(layer "B.Fab")
			(hide yes)
			(effects
				(font
					(size 1.016 1.016)
					(thickness 0.1524)
				)
				(justify mirror)
			)
		)
		(property "Device Type" "L805H42"
			(at 0 -5.7912 270)
			(unlocked yes)
			(layer "B.Fab")
			(hide yes)
			(effects
				(font
					(size 1.016 1.016)
					(thickness 0.1524)
				)
				(justify mirror)
			)
		)
		(duplicate_pad_numbers_are_jumpers no)
		(fp_line
			(start -0.889 1.7018)
			(end 0.889 1.7018)
			(stroke
				(width 0.1524)
				(type default)
			)
			(layer "B.SilkS")
		)
		(fp_line
			(start 0.889 1.7018)
			(end 0.889 -1.7018)
			(stroke
				(width 0.1524)
				(type default)
			)
			(layer "B.SilkS")
		)
		(fp_line
			(start -0.889 -1.7018)
			(end -0.889 1.7018)
			(stroke
				(width 0.1524)
				(type default)
			)
			(layer "B.SilkS")
		)
		(fp_line
			(start 0.889 -1.7018)
			(end -0.889 -1.7018)
			(stroke
				(width 0.1524)
				(type default)
			)
			(layer "B.SilkS")
		)
		(fp_rect
			(start 0.9652 1.778)
			(end -0.9652 -1.778)
			(stroke
				(width 0)
				(type default)
			)
			(fill no)
			(layer "B.CrtYd")
		)
		(fp_rect
			(start 0.9652 1.778)
			(end -0.9652 -1.778)
			(stroke
				(width 0)
				(type default)
			)
			(fill no)
			(layer "B.Fab")
		)
		(pad "1" smd rect
			(at 0 -0.9652 90)
			(size 1.397 1.143)
			(layers "B.Cu" "B.Mask" "B.Paste")
			(net "P3V3_STBY")
		)
		(pad "2" smd rect
			(at 0 0.9652 90)
			(size 1.397 1.143)
			(layers "B.Cu" "B.Mask" "B.Paste")
			(net "ADCAV33")
		)
	)
	(footprint ""
		(layer "B.Cu")
		(at 195.206366 -50.204116 180)
		(property "Reference" "R618"
			(at 0 0 0)
			(layer "B.SilkS")
			(hide yes)
			(effects
				(font
					(size 1.27 1.27)
				)
				(justify mirror)
			)
		)
		(property "Value" "10KR2F-2-GP"
			(at -0.064008 -3.993896 180)
			(unlocked yes)
			(layer "B.Fab")
			(hide yes)
			(effects
				(font
					(size 1.016 1.016)
					(thickness 0.1524)
				)
				(justify mirror)
			)
		)
		(property "Device Type" "R402H16"
			(at -0.064008 -5.517896 180)
			(unlocked yes)
			(layer "B.Fab")
			(hide yes)
			(effects
				(font
					(size 1.016 1.016)
					(thickness 0.1524)
				)
				(justify mirror)
			)
		)
		(duplicate_pad_numbers_are_jumpers no)
		(fp_line
			(start 0.508 -0.9398)
			(end 0.508 0.9398)
			(stroke
				(width 0.1524)
				(type default)
			)
			(layer "B.SilkS")
		)
		(fp_line
			(start -0.508 -0.9398)
			(end 0.508 -0.9398)
			(stroke
				(width 0.1524)
				(type default)
			)
			(layer "B.SilkS")
		)
		(fp_rect
			(start 0.508 0.9398)
			(end -0.508 -0.9398)
			(stroke
				(width 0)
				(type default)
			)
			(fill no)
			(layer "B.CrtYd")
		)
		(fp_rect
			(start 0.508 0.9398)
			(end -0.508 -0.9398)
			(stroke
				(width 0)
				(type default)
			)
			(fill no)
			(layer "B.Fab")
		)
		(pad "1" smd custom
			(at 0 -0.4445)
			(size 0.1397 0.1397)
			(layers "B.Cu" "B.Mask" "B.Paste")
			(net "P1V8")
			(options
				(clearance outline)
				(anchor circle)
			)
			(primitives
				(gr_poly
					(pts
						(arc
							(start -0.1778 0.2794)
							(mid -0.249642 0.249642)
							(end -0.2794 0.1778)
						)
						(arc
							(start -0.2794 -0.1778)
							(mid -0.249642 -0.249642)
							(end -0.1778 -0.2794)
						)
						(arc
							(start 0.1778 -0.2794)
							(mid 0.249642 -0.249642)
							(end 0.2794 -0.1778)
						)
						(arc
							(start 0.2794 0.1778)
							(mid 0.249642 0.249642)
							(end 0.1778 0.2794)
						)
					)
					(width 0)
					(fill yes)
				)
			)
		)
		(pad "2" smd custom
			(at 0 0.4445)
			(size 0.1397 0.1397)
			(layers "B.Cu" "B.Mask" "B.Paste")
			(net "AVSO_IDDTN18")
			(options
				(clearance outline)
				(anchor circle)
			)
			(primitives
				(gr_poly
					(pts
						(arc
							(start -0.1778 0.2794)
							(mid -0.249642 0.249642)
							(end -0.2794 0.1778)
						)
						(arc
							(start -0.2794 -0.1778)
							(mid -0.249642 -0.249642)
							(end -0.1778 -0.2794)
						)
						(arc
							(start 0.1778 -0.2794)
							(mid 0.249642 -0.249642)
							(end 0.2794 -0.1778)
						)
						(arc
							(start 0.2794 0.1778)
							(mid 0.249642 0.249642)
							(end 0.1778 0.2794)
						)
					)
					(width 0)
					(fill yes)
				)
			)
		)
	)
	(footprint ""
		(layer "B.Cu")
		(at 189.992 -73.152)
		(property "Reference" "TP161"
			(at 0 0 0)
			(layer "B.SilkS")
			(hide yes)
			(effects
				(font
					(size 1.27 1.27)
				)
				(justify mirror)
			)
		)
		(property "Value" "TPAD28-2-GP"
			(at 0.0127 -1.6637 0)
			(unlocked yes)
			(layer "B.Fab")
			(hide yes)
			(effects
				(font
					(size 1.016 1.016)
					(thickness 0.1524)
				)
				(justify mirror)
			)
		)
		(property "Device Type" "TPAD28"
			(at 0.0127 -3.1877 0)
			(unlocked yes)
			(layer "B.Fab")
			(hide yes)
			(effects
				(font
					(size 1.016 1.016)
					(thickness 0.1524)
				)
				(justify mirror)
			)
		)
		(duplicate_pad_numbers_are_jumpers no)
		(fp_poly
			(pts
				(arc
					(start 0.3556 0)
					(mid -0.3556 0)
					(end 0.3556 0)
				)
			)
			(stroke
				(width 0)
				(type default)
			)
			(fill no)
			(layer "B.CrtYd")
		)
		(fp_poly
			(pts
				(arc
					(start 0.6096 0)
					(mid -0.6096 0)
					(end 0.6096 0)
				)
			)
			(stroke
				(width 0)
				(type default)
			)
			(fill no)
			(layer "B.Fab")
		)
		(pad "1" smd circle
			(at 0 0 180)
			(size 0.7112 0.7112)
			(layers "B.Cu" "B.Mask" "B.Paste")
			(net "SPARE5")
		)
	)
	(footprint ""
		(layer "B.Cu")
		(at 190.8556 -63.2206 90)
		(property "Reference" "C398"
			(at 0 0 90)
			(layer "B.SilkS")
			(hide yes)
			(effects
				(font
					(size 1.27 1.27)
				)
				(justify mirror)
			)
		)
		(property "Value" "SCD1U6D3V1KX-GP"
			(at 2.8321 -1.7399 90)
			(unlocked yes)
			(layer "B.Fab")
			(hide yes)
			(effects
				(font
					(size 1.016 1.016)
					(thickness 0.1524)
				)
				(justify mirror)
			)
		)
		(property "Device Type" "C0201H13"
			(at 2.8321 -3.2639 90)
			(unlocked yes)
			(layer "B.Fab")
			(hide yes)
			(effects
				(font
					(size 1.016 1.016)
					(thickness 0.1524)
				)
				(justify mirror)
			)
		)
		(duplicate_pad_numbers_are_jumpers no)
		(fp_rect
			(start 0.2794 0.6477)
			(end -0.2794 -0.6477)
			(stroke
				(width 0)
				(type default)
			)
			(fill no)
			(layer "B.CrtYd")
		)
		(fp_rect
			(start 0.2794 0.6477)
			(end -0.2794 -0.6477)
			(stroke
				(width 0)
				(type default)
			)
			(fill no)
			(layer "B.Fab")
		)
		(pad "1" smd custom
			(at 0 -0.2794 270)
			(size 0.0762 0.0762)
			(layers "B.Cu" "B.Mask" "B.Paste")
			(net "P0V975")
			(options
				(clearance outline)
				(anchor circle)
			)
			(primitives
				(gr_poly
					(pts
						(arc
							(start 0.1524 0.127)
							(mid 0.137521 0.162921)
							(end 0.1016 0.1778)
						)
						(arc
							(start -0.1016 0.1778)
							(mid -0.137521 0.162921)
							(end -0.1524 0.127)
						)
						(arc
							(start -0.1524 -0.127)
							(mid -0.137521 -0.162921)
							(end -0.1016 -0.1778)
						)
						(arc
							(start 0.1016 -0.1778)
							(mid 0.137521 -0.162921)
							(end 0.1524 -0.127)
						)
					)
					(width 0)
					(fill yes)
				)
			)
		)
		(pad "2" smd custom
			(at 0 0.2794 270)
			(size 0.0762 0.0762)
			(layers "B.Cu" "B.Mask" "B.Paste")
			(net "GND")
			(options
				(clearance outline)
				(anchor circle)
			)
			(primitives
				(gr_poly
					(pts
						(arc
							(start 0.1524 0.127)
							(mid 0.137521 0.162921)
							(end 0.1016 0.1778)
						)
						(arc
							(start -0.1016 0.1778)
							(mid -0.137521 0.162921)
							(end -0.1524 0.127)
						)
						(arc
							(start -0.1524 -0.127)
							(mid -0.137521 -0.162921)
							(end -0.1016 -0.1778)
						)
						(arc
							(start 0.1016 -0.1778)
							(mid 0.137521 -0.162921)
							(end 0.1524 -0.127)
						)
					)
					(width 0)
					(fill yes)
				)
			)
		)
	)
	(footprint ""
		(layer "B.Cu")
		(at 195.5927 -63.23076 90)
		(property "Reference" "C409"
			(at 0 0 90)
			(layer "B.SilkS")
			(hide yes)
			(effects
				(font
					(size 1.27 1.27)
				)
				(justify mirror)
			)
		)
		(property "Value" "SCD1U6D3V1KX-GP"
			(at 2.8321 -1.7399 90)
			(unlocked yes)
			(layer "B.Fab")
			(hide yes)
			(effects
				(font
					(size 1.016 1.016)
					(thickness 0.1524)
				)
				(justify mirror)
			)
		)
		(property "Device Type" "C0201H13"
			(at 2.8321 -3.2639 90)
			(unlocked yes)
			(layer "B.Fab")
			(hide yes)
			(effects
				(font
					(size 1.016 1.016)
					(thickness 0.1524)
				)
				(justify mirror)
			)
		)
		(duplicate_pad_numbers_are_jumpers no)
		(fp_rect
			(start 0.2794 0.6477)
			(end -0.2794 -0.6477)
			(stroke
				(width 0)
				(type default)
			)
			(fill no)
			(layer "B.CrtYd")
		)
		(fp_rect
			(start 0.2794 0.6477)
			(end -0.2794 -0.6477)
			(stroke
				(width 0)
				(type default)
			)
			(fill no)
			(layer "B.Fab")
		)
		(pad "1" smd custom
			(at 0 -0.2794 270)
			(size 0.0762 0.0762)
			(layers "B.Cu" "B.Mask" "B.Paste")
			(net "P0V975")
			(options
				(clearance outline)
				(anchor circle)
			)
			(primitives
				(gr_poly
					(pts
						(arc
							(start 0.1524 0.127)
							(mid 0.137521 0.162921)
							(end 0.1016 0.1778)
						)
						(arc
							(start -0.1016 0.1778)
							(mid -0.137521 0.162921)
							(end -0.1524 0.127)
						)
						(arc
							(start -0.1524 -0.127)
							(mid -0.137521 -0.162921)
							(end -0.1016 -0.1778)
						)
						(arc
							(start 0.1016 -0.1778)
							(mid 0.137521 -0.162921)
							(end 0.1524 -0.127)
						)
					)
					(width 0)
					(fill yes)
				)
			)
		)
		(pad "2" smd custom
			(at 0 0.2794 270)
			(size 0.0762 0.0762)
			(layers "B.Cu" "B.Mask" "B.Paste")
			(net "GND")
			(options
				(clearance outline)
				(anchor circle)
			)
			(primitives
				(gr_poly
					(pts
						(arc
							(start 0.1524 0.127)
							(mid 0.137521 0.162921)
							(end 0.1016 0.1778)
						)
						(arc
							(start -0.1016 0.1778)
							(mid -0.137521 0.162921)
							(end -0.1524 0.127)
						)
						(arc
							(start -0.1524 -0.127)
							(mid -0.137521 -0.162921)
							(end -0.1016 -0.1778)
						)
						(arc
							(start 0.1016 -0.1778)
							(mid 0.137521 -0.162921)
							(end 0.1524 -0.127)
						)
					)
					(width 0)
					(fill yes)
				)
			)
		)
	)
	(footprint ""
		(layer "B.Cu")
		(at 55.800752 -149.300184)
		(property "Reference" "TP80"
			(at 0 0 0)
			(layer "B.SilkS")
			(hide yes)
			(effects
				(font
					(size 1.27 1.27)
				)
				(justify mirror)
			)
		)
		(property "Value" "TPAD28-2-GP"
			(at 0.0127 -1.6637 0)
			(unlocked yes)
			(layer "B.Fab")
			(hide yes)
			(effects
				(font
					(size 1.016 1.016)
					(thickness 0.1524)
				)
				(justify mirror)
			)
		)
		(property "Device Type" "TPAD28"
			(at 0.0127 -3.1877 0)
			(unlocked yes)
			(layer "B.Fab")
			(hide yes)
			(effects
				(font
					(size 1.016 1.016)
					(thickness 0.1524)
				)
				(justify mirror)
			)
		)
		(duplicate_pad_numbers_are_jumpers no)
		(fp_poly
			(pts
				(arc
					(start 0.3556 0)
					(mid -0.3556 0)
					(end 0.3556 0)
				)
			)
			(stroke
				(width 0)
				(type default)
			)
			(fill no)
			(layer "B.CrtYd")
		)
		(fp_poly
			(pts
				(arc
					(start 0.6096 0)
					(mid -0.6096 0)
					(end 0.6096 0)
				)
			)
			(stroke
				(width 0)
				(type default)
			)
			(fill no)
			(layer "B.Fab")
		)
		(pad "1" smd circle
			(at 0 0 180)
			(size 0.7112 0.7112)
			(layers "B.Cu" "B.Mask" "B.Paste")
			(net "JTAG_BMC_TMS")
		)
	)
	(footprint ""
		(layer "B.Cu")
		(at 174.1678 -77.9272 180)
		(property "Reference" "C342"
			(at 0 0 0)
			(layer "B.SilkS")
			(hide yes)
			(effects
				(font
					(size 1.27 1.27)
				)
				(justify mirror)
			)
		)
		(property "Value" "SC22U6D3V3MX-9-GP-U"
			(at 0 -2.8194 180)
			(unlocked yes)
			(layer "B.Fab")
			(hide yes)
			(effects
				(font
					(size 1.016 1.016)
					(thickness 0.1524)
				)
				(justify mirror)
			)
		)
		(property "Device Type" "C603H40"
			(at 0 -4.3434 180)
			(unlocked yes)
			(layer "B.Fab")
			(hide yes)
			(effects
				(font
					(size 1.016 1.016)
					(thickness 0.1524)
				)
				(justify mirror)
			)
		)
		(duplicate_pad_numbers_are_jumpers no)
		(fp_line
			(start -0.508 0)
			(end 0.508 0)
			(stroke
				(width 0.2032)
				(type default)
			)
			(layer "B.SilkS")
		)
		(fp_rect
			(start 0.5842 1.3335)
			(end -0.5842 -1.3335)
			(stroke
				(width 0)
				(type default)
			)
			(fill no)
			(layer "B.CrtYd")
		)
		(fp_rect
			(start 0.5842 1.3335)
			(end -0.5842 -1.3335)
			(stroke
				(width 0)
				(type default)
			)
			(fill no)
			(layer "B.Fab")
		)
		(pad "1" smd custom
			(at 0 -0.762)
			(size 0.2159 0.2159)
			(layers "B.Cu" "B.Mask" "B.Paste")
			(net "PLL_VDD")
			(options
				(clearance outline)
				(anchor circle)
			)
			(primitives
				(gr_poly
					(pts
						(arc
							(start -0.3302 0.4318)
							(mid -0.402042 0.402042)
							(end -0.4318 0.3302)
						)
						(arc
							(start -0.4318 -0.3302)
							(mid -0.402042 -0.402042)
							(end -0.3302 -0.4318)
						)
						(arc
							(start 0.3302 -0.4318)
							(mid 0.402042 -0.402042)
							(end 0.4318 -0.3302)
						)
						(arc
							(start 0.4318 0.3302)
							(mid 0.402042 0.402042)
							(end 0.3302 0.4318)
						)
					)
					(width 0)
					(fill yes)
				)
			)
		)
		(pad "2" smd custom
			(at 0 0.762)
			(size 0.2159 0.2159)
			(layers "B.Cu" "B.Mask" "B.Paste")
			(net "GND")
			(options
				(clearance outline)
				(anchor circle)
			)
			(primitives
				(gr_poly
					(pts
						(arc
							(start -0.3302 0.4318)
							(mid -0.402042 0.402042)
							(end -0.4318 0.3302)
						)
						(arc
							(start -0.4318 -0.3302)
							(mid -0.402042 -0.402042)
							(end -0.3302 -0.4318)
						)
						(arc
							(start 0.3302 -0.4318)
							(mid 0.402042 -0.402042)
							(end 0.4318 -0.3302)
						)
						(arc
							(start 0.4318 0.3302)
							(mid 0.402042 0.402042)
							(end 0.3302 0.4318)
						)
					)
					(width 0)
					(fill yes)
				)
			)
		)
	)
)
